#ISCELL
  mstr_misc dns *
  *
#ISCELL
  mstr_symbols design_note *
  *
#ISCELL
  mstr_symbols intel_corp_bpage *
  *
#CELL
  mstr_controller pi7c9x1172 *
  page183_i1
#ISCELL
  mstr_symbols gnd *
  page183_i10
#CELL
  mstr_discrete res *
  page183_i11
#CELL
  mstr_discrete res *
  page183_i12
#CELL
  mstr_discrete res *
  page183_i13
#CELL
  mstr_discrete res *
  page183_i14
#ISCELL
  mstr_symbols p3v3_stby *
  page183_i15
#ISCELL
  mstr_symbols p3v3_stby *
  page183_i16
#ISCELL
  mstr_symbols gnd *
  page183_i17
#ISCELL
  mstr_symbols gnd *
  page183_i18
#CELL
  mstr_discrete crystal *
  page183_i19
#ISCELL
  mstr_standard offpage *
  page183_i2
#CELL
  mstr_discrete cap *
  page183_i20
#CELL
  mstr_discrete cap *
  page183_i21
#ISCELL
  mstr_symbols gnd *
  page183_i22
#ISCELL
  mstr_symbols gnd *
  page183_i23
#CELL
  mstr_discrete res *
  page183_i24
#CELL
  mstr_discrete res *
  page183_i25
#ISCELL
  mstr_standard offpage *
  page183_i3
#CELL
  mstr_discrete res *
  page183_i30
#ISCELL
  mstr_symbols p3v3_stby *
  page183_i31
#ISCELL
  mstr_symbols gnd *
  page183_i32
#CELL
  mstr_discrete res *
  page183_i4
#CELL
  mstr_discrete res *
  page183_i48
#CELL
  mstr_discrete res *
  page183_i49
#ISCELL
  mstr_symbols p3v3_stby *
  page183_i5
#ISCELL
  mstr_standard offpage *
  page183_i50
#ISCELL
  mstr_standard offpage *
  page183_i51
#CELL
  mstr_discrete res *
  page183_i52
#CELL
  mstr_discrete res *
  page183_i53
#ISCELL
  mstr_standard offpage *
  page183_i54
#ISCELL
  mstr_standard offpage *
  page183_i55
#ISCELL
  mstr_standard offpage *
  page183_i56
#ISCELL
  mstr_standard offpage *
  page183_i57
#ISCELL
  mstr_symbols p3v3_stby *
  page183_i6
#CELL
  dev_discrete cap_a *
  page183_i7
#ISCELL
  mstr_symbols gnd *
  page183_i8
